# S9S_MB_2U (Grand Teton) — schematic netlist excerpt (pin names and nets, part order shuffled) for the footprints in the layout excerpt that follows; sources: Cadence DE-HDL packaged netlist, KiCad conversion of 03242023_DA0F0TMBIJ0_F0T_Motherboard_J_brd_V01_OCP.brd

R4465  Q_RES  3.9K 5% EMPTY  pkg 0402LF  page 196 : A = PD_USB_HUB_2_EQ ; B = GND
C1839  Q_CAP  0.1UF 25V 10% X7R  pkg 0402  page 159 : A = P12V_OCP_V3_2 ; B = GND
C1273  Q_CAP  47UF 4V 20% X6S  pkg C0805  page 189 : A = P1V8_PCH_PLL_AUX ; B = GND

(kicad_pcb
	(version 20260206)
	(generator "pcbnew")
	(generator_version "10.0")
	(general
		(thickness 1.6)
		(legacy_teardrops no)
	)
	(paper "A4")
	(title_block
		(title "03242023_DA0F0TMBIJ0_F0T_Motherboard_J_brd_V01_OCP.brd")
		(comment 1 "Grand Teton / footprints 5485-5487 of 6105")
	)
	(layers
		(0 "F.Cu" signal "TOP")
		(4 "In1.Cu" signal "GND")
		(6 "In2.Cu" signal "IN1")
		(8 "In3.Cu" signal "GND1")
		(10 "In4.Cu" signal "IN2")
		(12 "In5.Cu" signal "GND2")
		(14 "In6.Cu" signal "IN3")
		(16 "In7.Cu" signal "GND3")
		(18 "In8.Cu" signal "VCC")
		(20 "In9.Cu" signal "VCC1")
		(22 "In10.Cu" signal "GND4")
		(24 "In11.Cu" signal "IN4")
		(26 "In12.Cu" signal "GND5")
		(28 "In13.Cu" signal "IN5")
		(30 "In14.Cu" signal "GND6")
		(32 "In15.Cu" signal "IN6")
		(34 "In16.Cu" signal "GND7")
		(2 "B.Cu" signal "BOTTOM")
		(9 "F.Adhes" user "F.Adhesive")
		(11 "B.Adhes" user "B.Adhesive")
		(13 "F.Paste" user "Package Geometry/Pastemask Top")
		(15 "B.Paste" user "Package Geometry/Pastemask Bottom")
		(5 "F.SilkS" user "Ref Des/Silkscreen Top")
		(7 "B.SilkS" user "Ref Des/Silkscreen Bottom")
		(1 "F.Mask" user "Board Geometry/Soldermask Top")
		(3 "B.Mask" user "Board Geometry/Soldermask Bottom")
		(17 "Dwgs.User" user "User.Drawings")
		(19 "Cmts.User" user "User.Comments")
		(21 "Eco1.User" user "User.Eco1")
		(23 "Eco2.User" user "User.Eco2")
		(25 "Edge.Cuts" user "Board Geometry/Outline")
		(27 "Margin" user)
		(31 "F.CrtYd" user "Package Geometry/Place Bound Top")
		(29 "B.CrtYd" user "Package Geometry/Place Bound Bottom")
		(35 "F.Fab" user "Ref Des/Assembly Top")
		(33 "B.Fab" user "Ref Des/Assembly Bottom")
	)
	(footprint ""
		(layer "B.Cu")
		(at 350.319848 -54.435756 90)
		(property "Reference" "C1273"
			(at 0 0 90)
			(layer "B.SilkS")
			(hide yes)
			(effects
				(font
					(size 1.27 1.27)
				)
				(justify mirror)
			)
		)
		(property "Value" ""
			(at 0 0 90)
			(layer "B.Fab")
			(effects
				(font
					(size 1.27 1.27)
				)
				(justify mirror)
			)
		)
		(duplicate_pad_numbers_are_jumpers no)
		(fp_line
			(start 1.524 -0.762)
			(end -1.524 -0.762)
			(stroke
				(width 0.1524)
				(type default)
			)
			(layer "B.SilkS")
		)
		(fp_line
			(start -1.524 -0.762)
			(end -1.524 0.762)
			(stroke
				(width 0.1524)
				(type default)
			)
			(layer "B.SilkS")
		)
		(fp_line
			(start 1.524 0.762)
			(end 1.524 -0.762)
			(stroke
				(width 0.1524)
				(type default)
			)
			(layer "B.SilkS")
		)
		(fp_line
			(start -1.524 0.762)
			(end 1.524 0.762)
			(stroke
				(width 0.1524)
				(type default)
			)
			(layer "B.SilkS")
		)
		(fp_line
			(start 1.1049 -0.724916)
			(end 1.1049 0.724916)
			(stroke
				(width 0.1)
				(type default)
			)
			(layer "B.Fab")
		)
		(fp_line
			(start -1.1049 -0.724916)
			(end 1.1049 -0.724916)
			(stroke
				(width 0.1)
				(type default)
			)
			(layer "B.Fab")
		)
		(fp_line
			(start 1.1049 0.724916)
			(end -1.1049 0.724916)
			(stroke
				(width 0.1)
				(type default)
			)
			(layer "B.Fab")
		)
		(fp_line
			(start -1.1049 0.724916)
			(end -1.1049 -0.724916)
			(stroke
				(width 0.1)
				(type default)
			)
			(layer "B.Fab")
		)
		(pad "1" smd rect
			(at 0.889 0 90)
			(size 1.016 1.27)
			(layers "B.Cu" "B.Mask" "B.Paste")
			(net "P1V8_PCH_PLL_AUX")
		)
		(pad "2" smd rect
			(at -0.889 0 90)
			(size 1.016 1.27)
			(layers "B.Cu" "B.Mask" "B.Paste")
			(net "GND")
		)
	)
	(footprint ""
		(layer "B.Cu")
		(at 66.150744 -14.26464)
		(property "Reference" "C1839"
			(at 0 0 0)
			(layer "B.SilkS")
			(hide yes)
			(effects
				(font
					(size 1.27 1.27)
				)
				(justify mirror)
			)
		)
		(property "Value" ""
			(at 0 0 0)
			(layer "B.Fab")
			(effects
				(font
					(size 1.27 1.27)
				)
				(justify mirror)
			)
		)
		(duplicate_pad_numbers_are_jumpers no)
		(fp_line
			(start -0.7874 -0.4064)
			(end -0.7874 0.4064)
			(stroke
				(width 0.1524)
				(type default)
			)
			(layer "B.SilkS")
		)
		(fp_line
			(start -0.7874 0.4064)
			(end 0.7874 0.4064)
			(stroke
				(width 0.1524)
				(type default)
			)
			(layer "B.SilkS")
		)
		(fp_line
			(start 0.7874 -0.4064)
			(end -0.7874 -0.4064)
			(stroke
				(width 0.1524)
				(type default)
			)
			(layer "B.SilkS")
		)
		(fp_line
			(start 0.7874 0.4064)
			(end 0.7874 -0.4064)
			(stroke
				(width 0.1524)
				(type default)
			)
			(layer "B.SilkS")
		)
		(fp_line
			(start -0.67945 -0.3048)
			(end -0.67945 0.3048)
			(stroke
				(width 0.1)
				(type default)
			)
			(layer "B.Fab")
		)
		(fp_line
			(start -0.67945 0.3048)
			(end -0.120396 0.3048)
			(stroke
				(width 0.1)
				(type default)
			)
			(layer "B.Fab")
		)
		(fp_line
			(start -0.12065 -0.3048)
			(end -0.67945 -0.3048)
			(stroke
				(width 0.1)
				(type default)
			)
			(layer "B.Fab")
		)
		(fp_line
			(start -0.12065 -0.2794)
			(end -0.12065 -0.3048)
			(stroke
				(width 0.1)
				(type default)
			)
			(layer "B.Fab")
		)
		(fp_line
			(start -0.120396 0.2794)
			(end 0.12065 0.2794)
			(stroke
				(width 0.1)
				(type default)
			)
			(layer "B.Fab")
		)
		(fp_line
			(start -0.120396 0.3048)
			(end -0.120396 0.2794)
			(stroke
				(width 0.1)
				(type default)
			)
			(layer "B.Fab")
		)
		(fp_line
			(start 0.12065 -0.305054)
			(end 0.12065 -0.2794)
			(stroke
				(width 0.1)
				(type default)
			)
			(layer "B.Fab")
		)
		(fp_line
			(start 0.12065 -0.2794)
			(end -0.12065 -0.2794)
			(stroke
				(width 0.1)
				(type default)
			)
			(layer "B.Fab")
		)
		(fp_line
			(start 0.12065 0.2794)
			(end 0.12065 0.3048)
			(stroke
				(width 0.1)
				(type default)
			)
			(layer "B.Fab")
		)
		(fp_line
			(start 0.12065 0.3048)
			(end 0.67945 0.3048)
			(stroke
				(width 0.1)
				(type default)
			)
			(layer "B.Fab")
		)
		(fp_line
			(start 0.67945 -0.305054)
			(end 0.12065 -0.305054)
			(stroke
				(width 0.1)
				(type default)
			)
			(layer "B.Fab")
		)
		(fp_line
			(start 0.67945 0.3048)
			(end 0.67945 -0.305054)
			(stroke
				(width 0.1)
				(type default)
			)
			(layer "B.Fab")
		)
		(pad "1" smd circle
			(at 0.40005 0 180)
			(size 0 0)
			(layers "B.Cu" "B.Mask" "B.Paste")
			(net "P12V_OCP_V3_2")
		)
		(pad "2" smd circle
			(at -0.40005 0 180)
			(size 0 0)
			(layers "B.Cu" "B.Mask" "B.Paste")
			(net "GND")
		)
	)
	(footprint ""
		(layer "B.Cu")
		(at 144.50187 -27.843988 180)
		(property "Reference" "R4465"
			(at 0 0 0)
			(layer "B.SilkS")
			(hide yes)
			(effects
				(font
					(size 1.27 1.27)
				)
				(justify mirror)
			)
		)
		(property "Value" ""
			(at 0 0 0)
			(layer "B.Fab")
			(effects
				(font
					(size 1.27 1.27)
				)
				(justify mirror)
			)
		)
		(duplicate_pad_numbers_are_jumpers no)
		(fp_line
			(start 0.7874 0.4064)
			(end 0.7874 -0.4064)
			(stroke
				(width 0.1524)
				(type default)
			)
			(layer "B.SilkS")
		)
		(fp_line
			(start 0.7874 -0.4064)
			(end -0.7874 -0.4064)
			(stroke
				(width 0.1524)
				(type default)
			)
			(layer "B.SilkS")
		)
		(fp_line
			(start -0.7874 0.4064)
			(end 0.7874 0.4064)
			(stroke
				(width 0.1524)
				(type default)
			)
			(layer "B.SilkS")
		)
		(fp_line
			(start -0.7874 -0.4064)
			(end -0.7874 0.4064)
			(stroke
				(width 0.1524)
				(type default)
			)
			(layer "B.SilkS")
		)
		(fp_line
			(start 0.67945 0.3048)
			(end 0.67945 -0.305054)
			(stroke
				(width 0.1)
				(type default)
			)
			(layer "B.Fab")
		)
		(fp_line
			(start 0.67945 -0.305054)
			(end 0.12065 -0.305054)
			(stroke
				(width 0.1)
				(type default)
			)
			(layer "B.Fab")
		)
		(fp_line
			(start 0.12065 0.3048)
			(end 0.67945 0.3048)
			(stroke
				(width 0.1)
				(type default)
			)
			(layer "B.Fab")
		)
		(fp_line
			(start 0.12065 0.2794)
			(end 0.12065 0.3048)
			(stroke
				(width 0.1)
				(type default)
			)
			(layer "B.Fab")
		)
		(fp_line
			(start 0.12065 -0.2794)
			(end -0.12065 -0.2794)
			(stroke
				(width 0.1)
				(type default)
			)
			(layer "B.Fab")
		)
		(fp_line
			(start 0.12065 -0.305054)
			(end 0.12065 -0.2794)
			(stroke
				(width 0.1)
				(type default)
			)
			(layer "B.Fab")
		)
		(fp_line
			(start -0.120396 0.3048)
			(end -0.120396 0.2794)
			(stroke
				(width 0.1)
				(type default)
			)
			(layer "B.Fab")
		)
		(fp_line
			(start -0.120396 0.2794)
			(end 0.12065 0.2794)
			(stroke
				(width 0.1)
				(type default)
			)
			(layer "B.Fab")
		)
		(fp_line
			(start -0.12065 -0.2794)
			(end -0.12065 -0.3048)
			(stroke
				(width 0.1)
				(type default)
			)
			(layer "B.Fab")
		)
		(fp_line
			(start -0.12065 -0.3048)
			(end -0.67945 -0.3048)
			(stroke
				(width 0.1)
				(type default)
			)
			(layer "B.Fab")
		)
		(fp_line
			(start -0.67945 0.3048)
			(end -0.120396 0.3048)
			(stroke
				(width 0.1)
				(type default)
			)
			(layer "B.Fab")
		)
		(fp_line
			(start -0.67945 -0.3048)
			(end -0.67945 0.3048)
			(stroke
				(width 0.1)
				(type default)
			)
			(layer "B.Fab")
		)
		(pad "1" smd circle
			(at 0.40005 0)
			(size 0 0)
			(layers "B.Cu" "B.Mask" "B.Paste")
			(net "PD_USB_HUB_2_EQ")
		)
		(pad "2" smd circle
			(at -0.40005 0)
			(size 0 0)
			(layers "B.Cu" "B.Mask" "B.Paste")
			(net "GND")
		)
	)
)
